(kicad_pcb
	(version 20260206)
	(generator "pcbnew")
	(generator_version "10.0")
	(general
		(thickness 1.6)
		(legacy_teardrops no)
	)
	(paper "A4")
	(title_block
		(title "Bryce Canyon_IOM_M2_16342-2_OCP.brd")
		(comment 1 "Bryce Canyon / footprints 505-511 of 1146")
	)
	(layers
		(0 "F.Cu" signal "TOP")
		(4 "In1.Cu" signal "L2GND")
		(6 "In2.Cu" signal "L3")
		(8 "In3.Cu" signal "L4VCC")
		(10 "In4.Cu" signal "L5VCC")
		(12 "In5.Cu" signal "L6")
		(14 "In6.Cu" signal "L7GND")
		(2 "B.Cu" signal "BOTTOM")
		(9 "F.Adhes" user "F.Adhesive")
		(11 "B.Adhes" user "B.Adhesive")
		(13 "F.Paste" user "Package Geometry/Pastemask Top")
		(15 "B.Paste" user "Package Geometry/Pastemask Bottom")
		(5 "F.SilkS" user "Ref Des/Silkscreen Top")
		(7 "B.SilkS" user "Ref Des/Silkscreen Bottom")
		(1 "F.Mask" user "Board Geometry/Soldermask Top")
		(3 "B.Mask" user "Board Geometry/Soldermask Bottom")
		(17 "Dwgs.User" user "User.Drawings")
		(19 "Cmts.User" user "User.Comments")
		(21 "Eco1.User" user "User.Eco1")
		(23 "Eco2.User" user "User.Eco2")
		(25 "Edge.Cuts" user "Board Geometry/Outline")
		(27 "Margin" user)
		(31 "F.CrtYd" user "Package Geometry/Place Bound Top")
		(29 "B.CrtYd" user "Package Geometry/Place Bound Bottom")
		(35 "F.Fab" user "Ref Des/Assembly Top")
		(33 "B.Fab" user "Ref Des/Assembly Bottom")
	)
	(footprint ""
		(layer "F.Cu")
		(at 39.0398 -158.623 180)
		(property "Reference" "R328"
			(at 0 0 180)
			(layer "F.SilkS")
			(hide yes)
			(effects
				(font
					(size 1.27 1.27)
				)
			)
		)
		(property "Value" "0R2J-2-GP"
			(at 0.064008 -3.993896 180)
			(unlocked yes)
			(layer "F.Fab")
			(hide yes)
			(effects
				(font
					(size 1.016 1.016)
					(thickness 0.1524)
				)
			)
		)
		(property "Device Type" "R402H16"
			(at 0.064008 -5.517896 180)
			(unlocked yes)
			(layer "F.Fab")
			(hide yes)
			(effects
				(font
					(size 1.016 1.016)
					(thickness 0.1524)
				)
			)
		)
		(duplicate_pad_numbers_are_jumpers no)
		(fp_line
			(start 0.508 -0.9398)
			(end -0.508 -0.9398)
			(stroke
				(width 0.1524)
				(type default)
			)
			(layer "F.SilkS")
		)
		(fp_line
			(start -0.508 -0.9398)
			(end -0.508 0.9398)
			(stroke
				(width 0.1524)
				(type default)
			)
			(layer "F.SilkS")
		)
		(fp_rect
			(start -0.508 0.9398)
			(end 0.508 -0.9398)
			(stroke
				(width 0)
				(type default)
			)
			(fill no)
			(layer "F.CrtYd")
		)
		(fp_rect
			(start -0.508 0.9398)
			(end 0.508 -0.9398)
			(stroke
				(width 0)
				(type default)
			)
			(fill no)
			(layer "F.Fab")
		)
		(pad "1" smd custom
			(at 0 -0.4445 180)
			(size 0.1397 0.1397)
			(layers "F.Cu" "F.Mask" "F.Paste")
			(net "UART_COMP_OUT_TX_R")
			(options
				(clearance outline)
				(anchor circle)
			)
			(primitives
				(gr_poly
					(pts
						(arc
							(start -0.1778 -0.2794)
							(mid -0.249642 -0.249642)
							(end -0.2794 -0.1778)
						)
						(arc
							(start -0.2794 0.1778)
							(mid -0.249642 0.249642)
							(end -0.1778 0.2794)
						)
						(arc
							(start 0.1778 0.2794)
							(mid 0.249642 0.249642)
							(end 0.2794 0.1778)
						)
						(arc
							(start 0.2794 -0.1778)
							(mid 0.249642 -0.249642)
							(end 0.1778 -0.2794)
						)
					)
					(width 0)
					(fill yes)
				)
			)
		)
		(pad "2" smd custom
			(at 0 0.4445 180)
			(size 0.1397 0.1397)
			(layers "F.Cu" "F.Mask" "F.Paste")
			(net "UART_COMP_OUT_TX")
			(options
				(clearance outline)
				(anchor circle)
			)
			(primitives
				(gr_poly
					(pts
						(arc
							(start -0.1778 -0.2794)
							(mid -0.249642 -0.249642)
							(end -0.2794 -0.1778)
						)
						(arc
							(start -0.2794 0.1778)
							(mid -0.249642 0.249642)
							(end -0.1778 0.2794)
						)
						(arc
							(start 0.1778 0.2794)
							(mid 0.249642 0.249642)
							(end 0.2794 0.1778)
						)
						(arc
							(start 0.2794 -0.1778)
							(mid 0.249642 -0.249642)
							(end 0.1778 -0.2794)
						)
					)
					(width 0)
					(fill yes)
				)
			)
		)
	)
	(footprint ""
		(layer "F.Cu")
		(at 72.822562 -156.644594 180)
		(property "Reference" "R305"
			(at 0 0 180)
			(layer "F.SilkS")
			(hide yes)
			(effects
				(font
					(size 1.27 1.27)
				)
			)
		)
		(property "Value" "10KR2F-2-GP"
			(at 0.064008 -3.993896 180)
			(unlocked yes)
			(layer "F.Fab")
			(hide yes)
			(effects
				(font
					(size 1.016 1.016)
					(thickness 0.1524)
				)
			)
		)
		(property "Device Type" "R402H16"
			(at 0.064008 -5.517896 180)
			(unlocked yes)
			(layer "F.Fab")
			(hide yes)
			(effects
				(font
					(size 1.016 1.016)
					(thickness 0.1524)
				)
			)
		)
		(duplicate_pad_numbers_are_jumpers no)
		(fp_line
			(start 0.508 -0.9398)
			(end -0.508 -0.9398)
			(stroke
				(width 0.1524)
				(type default)
			)
			(layer "F.SilkS")
		)
		(fp_line
			(start -0.508 -0.9398)
			(end -0.508 0.9398)
			(stroke
				(width 0.1524)
				(type default)
			)
			(layer "F.SilkS")
		)
		(fp_rect
			(start -0.508 0.9398)
			(end 0.508 -0.9398)
			(stroke
				(width 0)
				(type default)
			)
			(fill no)
			(layer "F.CrtYd")
		)
		(fp_rect
			(start -0.508 0.9398)
			(end 0.508 -0.9398)
			(stroke
				(width 0)
				(type default)
			)
			(fill no)
			(layer "F.Fab")
		)
		(pad "1" smd custom
			(at 0 -0.4445 180)
			(size 0.1397 0.1397)
			(layers "F.Cu" "F.Mask" "F.Paste")
			(net "P3V3_STBY")
			(options
				(clearance outline)
				(anchor circle)
			)
			(primitives
				(gr_poly
					(pts
						(arc
							(start -0.1778 -0.2794)
							(mid -0.249642 -0.249642)
							(end -0.2794 -0.1778)
						)
						(arc
							(start -0.2794 0.1778)
							(mid -0.249642 0.249642)
							(end -0.1778 0.2794)
						)
						(arc
							(start 0.1778 0.2794)
							(mid 0.249642 0.249642)
							(end 0.2794 0.1778)
						)
						(arc
							(start 0.2794 -0.1778)
							(mid 0.249642 -0.249642)
							(end 0.1778 -0.2794)
						)
					)
					(width 0)
					(fill yes)
				)
			)
		)
		(pad "2" smd custom
			(at 0 0.4445 180)
			(size 0.1397 0.1397)
			(layers "F.Cu" "F.Mask" "F.Paste")
			(net "FM_OSC_50M_EN")
			(options
				(clearance outline)
				(anchor circle)
			)
			(primitives
				(gr_poly
					(pts
						(arc
							(start -0.1778 -0.2794)
							(mid -0.249642 -0.249642)
							(end -0.2794 -0.1778)
						)
						(arc
							(start -0.2794 0.1778)
							(mid -0.249642 0.249642)
							(end -0.1778 0.2794)
						)
						(arc
							(start 0.1778 0.2794)
							(mid 0.249642 0.249642)
							(end 0.2794 0.1778)
						)
						(arc
							(start 0.2794 -0.1778)
							(mid 0.249642 -0.249642)
							(end 0.1778 -0.2794)
						)
					)
					(width 0)
					(fill yes)
				)
			)
		)
	)
	(footprint ""
		(layer "F.Cu")
		(at 181.4322 -6.8326 -90)
		(property "Reference" "Q28"
			(at 0 0 270)
			(layer "F.SilkS")
			(hide yes)
			(effects
				(font
					(size 1.27 1.27)
				)
			)
		)
		(property "Value" "2N7002K-1-GP"
			(at 0.127 -8.9662 270)
			(unlocked yes)
			(layer "F.Fab")
			(hide yes)
			(effects
				(font
					(size 1.016 1.016)
					(thickness 0.1524)
				)
			)
		)
		(property "Device Type" "SOT23DGS2D4H44"
			(at 0.127 -10.4902 270)
			(unlocked yes)
			(layer "F.Fab")
			(hide yes)
			(effects
				(font
					(size 1.016 1.016)
					(thickness 0.1524)
				)
			)
		)
		(duplicate_pad_numbers_are_jumpers no)
		(fp_line
			(start -1.651 1.778)
			(end 1.651 1.778)
			(stroke
				(width 0.1524)
				(type default)
			)
			(layer "F.SilkS")
		)
		(fp_line
			(start 1.651 1.778)
			(end 1.651 -1.778)
			(stroke
				(width 0.1524)
				(type default)
			)
			(layer "F.SilkS")
		)
		(fp_line
			(start -1.651 -1.778)
			(end -1.651 1.778)
			(stroke
				(width 0.1524)
				(type default)
			)
			(layer "F.SilkS")
		)
		(fp_line
			(start 1.651 -1.778)
			(end -1.651 -1.778)
			(stroke
				(width 0.1524)
				(type default)
			)
			(layer "F.SilkS")
		)
		(fp_poly
			(pts
				(xy -1.778 1.8796) (xy -1.778 -1.8796) (xy 1.778 -1.8796) (xy 1.778 1.8796)
			)
			(stroke
				(width 0)
				(type default)
			)
			(fill no)
			(layer "F.CrtYd")
		)
		(fp_poly
			(pts
				(xy -1.778 1.8796) (xy -1.778 -1.8796) (xy 1.778 -1.8796) (xy 1.778 1.8796)
			)
			(stroke
				(width 0)
				(type default)
			)
			(fill no)
			(layer "F.Fab")
		)
		(pad "D" smd custom
			(at 0 -0.9525 270)
			(size 0.1905 0.1905)
			(layers "F.Cu" "F.Mask" "F.Paste")
			(net "BMC_ML_PWR_BLUE_LED_L")
			(options
				(clearance outline)
				(anchor circle)
			)
			(primitives
				(gr_poly
					(pts
						(arc
							(start -0.1778 0.5715)
							(mid -0.321484 0.511984)
							(end -0.381 0.3683)
						)
						(arc
							(start -0.381 -0.3683)
							(mid -0.321484 -0.511984)
							(end -0.1778 -0.5715)
						)
						(arc
							(start 0.1778 -0.5715)
							(mid 0.321484 -0.511984)
							(end 0.381 -0.3683)
						)
						(arc
							(start 0.381 0.3683)
							(mid 0.321484 0.511984)
							(end 0.1778 0.5715)
						)
					)
					(width 0)
					(fill yes)
				)
			)
		)
		(pad "G" smd custom
			(at -0.98425 0.9525 270)
			(size 0.1905 0.1905)
			(layers "F.Cu" "F.Mask" "F.Paste")
			(net "BMC_ML_PWR_BLUE_LED_R")
			(options
				(clearance outline)
				(anchor circle)
			)
			(primitives
				(gr_poly
					(pts
						(arc
							(start -0.1778 0.5715)
							(mid -0.321484 0.511984)
							(end -0.381 0.3683)
						)
						(arc
							(start -0.381 -0.3683)
							(mid -0.321484 -0.511984)
							(end -0.1778 -0.5715)
						)
						(arc
							(start 0.1778 -0.5715)
							(mid 0.321484 -0.511984)
							(end 0.381 -0.3683)
						)
						(arc
							(start 0.381 0.3683)
							(mid 0.321484 0.511984)
							(end 0.1778 0.5715)
						)
					)
					(width 0)
					(fill yes)
				)
			)
		)
		(pad "S" smd custom
			(at 0.98425 0.9525 270)
			(size 0.1905 0.1905)
			(layers "F.Cu" "F.Mask" "F.Paste")
			(net "GND")
			(options
				(clearance outline)
				(anchor circle)
			)
			(primitives
				(gr_poly
					(pts
						(arc
							(start -0.1778 0.5715)
							(mid -0.321484 0.511984)
							(end -0.381 0.3683)
						)
						(arc
							(start -0.381 -0.3683)
							(mid -0.321484 -0.511984)
							(end -0.1778 -0.5715)
						)
						(arc
							(start 0.1778 -0.5715)
							(mid 0.321484 -0.511984)
							(end 0.381 -0.3683)
						)
						(arc
							(start 0.381 0.3683)
							(mid 0.321484 0.511984)
							(end 0.1778 0.5715)
						)
					)
					(width 0)
					(fill yes)
				)
			)
		)
	)
	(footprint ""
		(layer "F.Cu")
		(at 88.0872 -138.1252 90)
		(property "Reference" "R136"
			(at 0 0 90)
			(layer "F.SilkS")
			(hide yes)
			(effects
				(font
					(size 1.27 1.27)
				)
			)
		)
		(property "Value" "8K2R2J-3-GP"
			(at 0.064008 -3.993896 90)
			(unlocked yes)
			(layer "F.Fab")
			(hide yes)
			(effects
				(font
					(size 1.016 1.016)
					(thickness 0.1524)
				)
			)
		)
		(property "Device Type" "R402H16"
			(at 0.064008 -5.517896 90)
			(unlocked yes)
			(layer "F.Fab")
			(hide yes)
			(effects
				(font
					(size 1.016 1.016)
					(thickness 0.1524)
				)
			)
		)
		(duplicate_pad_numbers_are_jumpers no)
		(fp_line
			(start 0.508 -0.9398)
			(end -0.508 -0.9398)
			(stroke
				(width 0.1524)
				(type default)
			)
			(layer "F.SilkS")
		)
		(fp_line
			(start -0.508 -0.9398)
			(end -0.508 0.9398)
			(stroke
				(width 0.1524)
				(type default)
			)
			(layer "F.SilkS")
		)
		(fp_rect
			(start -0.508 0.9398)
			(end 0.508 -0.9398)
			(stroke
				(width 0)
				(type default)
			)
			(fill no)
			(layer "F.CrtYd")
		)
		(fp_rect
			(start -0.508 0.9398)
			(end 0.508 -0.9398)
			(stroke
				(width 0)
				(type default)
			)
			(fill no)
			(layer "F.Fab")
		)
		(pad "1" smd custom
			(at 0 -0.4445 90)
			(size 0.1397 0.1397)
			(layers "F.Cu" "F.Mask" "F.Paste")
			(net "EEPROM_A0")
			(options
				(clearance outline)
				(anchor circle)
			)
			(primitives
				(gr_poly
					(pts
						(arc
							(start -0.1778 -0.2794)
							(mid -0.249642 -0.249642)
							(end -0.2794 -0.1778)
						)
						(arc
							(start -0.2794 0.1778)
							(mid -0.249642 0.249642)
							(end -0.1778 0.2794)
						)
						(arc
							(start 0.1778 0.2794)
							(mid 0.249642 0.249642)
							(end 0.2794 0.1778)
						)
						(arc
							(start 0.2794 -0.1778)
							(mid 0.249642 -0.249642)
							(end 0.1778 -0.2794)
						)
					)
					(width 0)
					(fill yes)
				)
			)
		)
		(pad "2" smd custom
			(at 0 0.4445 90)
			(size 0.1397 0.1397)
			(layers "F.Cu" "F.Mask" "F.Paste")
			(net "GND")
			(options
				(clearance outline)
				(anchor circle)
			)
			(primitives
				(gr_poly
					(pts
						(arc
							(start -0.1778 -0.2794)
							(mid -0.249642 -0.249642)
							(end -0.2794 -0.1778)
						)
						(arc
							(start -0.2794 0.1778)
							(mid -0.249642 0.249642)
							(end -0.1778 0.2794)
						)
						(arc
							(start 0.1778 0.2794)
							(mid 0.249642 0.249642)
							(end 0.2794 0.1778)
						)
						(arc
							(start 0.2794 -0.1778)
							(mid 0.249642 -0.249642)
							(end 0.1778 -0.2794)
						)
					)
					(width 0)
					(fill yes)
				)
			)
		)
	)
	(footprint ""
		(layer "F.Cu")
		(at 80.7212 -133.6294 90)
		(property "Reference" "C32"
			(at 0 0 90)
			(layer "F.SilkS")
			(hide yes)
			(effects
				(font
					(size 1.27 1.27)
				)
			)
		)
		(property "Value" "SCD1U16V2KX-3GP"
			(at 1.1811 -2.7051 90)
			(unlocked yes)
			(layer "F.Fab")
			(hide yes)
			(effects
				(font
					(size 1.016 1.016)
					(thickness 0.1524)
				)
			)
		)
		(property "Device Type" "C402H22"
			(at 1.1811 -4.2291 90)
			(unlocked yes)
			(layer "F.Fab")
			(hide yes)
			(effects
				(font
					(size 1.016 1.016)
					(thickness 0.1524)
				)
			)
		)
		(duplicate_pad_numbers_are_jumpers no)
		(fp_rect
			(start -0.4318 0.9525)
			(end 0.4318 -0.9525)
			(stroke
				(width 0)
				(type default)
			)
			(fill no)
			(layer "F.CrtYd")
		)
		(fp_rect
			(start -0.4318 0.9525)
			(end 0.4318 -0.9525)
			(stroke
				(width 0)
				(type default)
			)
			(fill no)
			(layer "F.Fab")
		)
		(pad "1" smd custom
			(at 0 -0.4445 90)
			(size 0.1524 0.1524)
			(layers "F.Cu" "F.Mask" "F.Paste")
			(net "DEBUG_HDR_UART_SEL")
			(options
				(clearance outline)
				(anchor circle)
			)
			(primitives
				(gr_poly
					(pts
						(arc
							(start 0.3048 -0.2032)
							(mid 0.275042 -0.275042)
							(end 0.2032 -0.3048)
						)
						(arc
							(start -0.2032 -0.3048)
							(mid -0.275042 -0.275042)
							(end -0.3048 -0.2032)
						)
						(arc
							(start -0.3048 0.2032)
							(mid -0.275042 0.275042)
							(end -0.2032 0.3048)
						)
						(arc
							(start 0.2032 0.3048)
							(mid 0.275042 0.275042)
							(end 0.3048 0.2032)
						)
					)
					(width 0)
					(fill yes)
				)
			)
		)
		(pad "2" smd custom
			(at 0 0.4445 90)
			(size 0.1524 0.1524)
			(layers "F.Cu" "F.Mask" "F.Paste")
			(net "GND")
			(options
				(clearance outline)
				(anchor circle)
			)
			(primitives
				(gr_poly
					(pts
						(arc
							(start 0.3048 -0.2032)
							(mid 0.275042 -0.275042)
							(end 0.2032 -0.3048)
						)
						(arc
							(start -0.2032 -0.3048)
							(mid -0.275042 -0.275042)
							(end -0.3048 -0.2032)
						)
						(arc
							(start -0.3048 0.2032)
							(mid -0.275042 0.275042)
							(end -0.2032 0.3048)
						)
						(arc
							(start 0.2032 0.3048)
							(mid 0.275042 0.275042)
							(end 0.3048 0.2032)
						)
					)
					(width 0)
					(fill yes)
				)
			)
		)
	)
	(footprint ""
		(layer "F.Cu")
		(at 51.5112 -129.5654)
		(property "Reference" "TP9"
			(at 0 0 0)
			(layer "F.SilkS")
			(hide yes)
			(effects
				(font
					(size 1.27 1.27)
				)
			)
		)
		(property "Value" "TPAD28-2-GP"
			(at -0.0127 -1.6637 0)
			(unlocked yes)
			(layer "F.Fab")
			(hide yes)
			(effects
				(font
					(size 1.016 1.016)
					(thickness 0.1524)
				)
			)
		)
		(property "Device Type" "TPAD28"
			(at -0.0127 -3.1877 0)
			(unlocked yes)
			(layer "F.Fab")
			(hide yes)
			(effects
				(font
					(size 1.016 1.016)
					(thickness 0.1524)
				)
			)
		)
		(duplicate_pad_numbers_are_jumpers no)
		(fp_poly
			(pts
				(arc
					(start 0.3556 0)
					(mid -0.3556 0)
					(end 0.3556 0)
				)
			)
			(stroke
				(width 0)
				(type default)
			)
			(fill no)
			(layer "F.CrtYd")
		)
		(fp_poly
			(pts
				(arc
					(start 0.6096 0)
					(mid -0.6096 0)
					(end 0.6096 0)
				)
			)
			(stroke
				(width 0)
				(type default)
			)
			(fill no)
			(layer "F.Fab")
		)
		(pad "1" smd circle
			(at 0 0)
			(size 0.7112 0.7112)
			(layers "F.Cu" "F.Mask" "F.Paste")
			(net "TP_BMC0_LPC_LAD0")
		)
	)
	(footprint ""
		(layer "F.Cu")
		(at 50.27168 -184.020714)
		(property "Reference" "C175"
			(at 0 0 0)
			(layer "F.SilkS")
			(hide yes)
			(effects
				(font
					(size 1.27 1.27)
				)
			)
		)
		(property "Value" "ST150U6D3VDM-28-GP"
			(at 0 -9.6012 0)
			(unlocked yes)
			(layer "F.Fab")
			(hide yes)
			(effects
				(font
					(size 1.016 1.016)
					(thickness 0.1524)
				)
			)
		)
		(property "Device Type" "CT7343H83"
			(at 0 -11.1252 0)
			(unlocked yes)
			(layer "F.Fab")
			(hide yes)
			(effects
				(font
					(size 1.016 1.016)
					(thickness 0.1524)
				)
			)
		)
		(duplicate_pad_numbers_are_jumpers no)
		(fp_line
			(start -2.286 -4.8768)
			(end -2.286 -2.032)
			(stroke
				(width 0.1524)
				(type default)
			)
			(layer "F.SilkS")
		)
		(fp_line
			(start -2.286 4.8768)
			(end -2.286 2.032)
			(stroke
				(width 0.1524)
				(type default)
			)
			(layer "F.SilkS")
		)
		(fp_line
			(start 2.1082 -4.699)
			(end -2.1082 -4.699)
			(stroke
				(width 0.508)
				(type default)
			)
			(layer "F.SilkS")
		)
		(fp_line
			(start 2.286 -4.8768)
			(end -2.286 -4.8768)
			(stroke
				(width 0.1524)
				(type default)
			)
			(layer "F.SilkS")
		)
		(fp_line
			(start 2.286 -2.032)
			(end 2.286 -4.8768)
			(stroke
				(width 0.1524)
				(type default)
			)
			(layer "F.SilkS")
		)
		(fp_line
			(start 2.286 2.032)
			(end 2.286 4.8768)
			(stroke
				(width 0.1524)
				(type default)
			)
			(layer "F.SilkS")
		)
		(fp_line
			(start 2.286 4.8768)
			(end -2.286 4.8768)
			(stroke
				(width 0.1524)
				(type default)
			)
			(layer "F.SilkS")
		)
		(fp_rect
			(start -2.1463 3.6449)
			(end 2.1463 -3.6449)
			(stroke
				(width 0)
				(type default)
			)
			(fill no)
			(layer "F.CrtYd")
		)
		(fp_poly
			(pts
				(xy -2.54 4.953) (xy -2.54 4.2926) (xy -3.81 4.2926) (xy -3.81 -4.2926) (xy -2.54 -4.2926) (xy -2.54 -4.953)
				(xy 2.54 -4.953) (xy 2.54 -4.2926) (xy 3.81 -4.2926) (xy 3.81 -1.6256) (xy 2.1463 -1.6256) (xy 2.1463 -3.6449)
				(xy -2.1463 -3.6449) (xy -2.1463 3.6449) (xy 2.1463 3.6449) (xy 2.1463 -1.6129) (xy 3.81 -1.6129)
				(xy 3.81 4.2926) (xy 2.54 4.2926) (xy 2.54 4.953)
			)
			(stroke
				(width 0)
				(type default)
			)
			(fill no)
			(layer "F.CrtYd")
		)
		(fp_rect
			(start -3.81 4.2926)
			(end -2.54 -4.2926)
			(stroke
				(width 0)
				(type default)
			)
			(fill no)
			(layer "F.Fab")
		)
		(fp_rect
			(start -2.54 4.953)
			(end 2.54 -4.953)
			(stroke
				(width 0)
				(type default)
			)
			(fill no)
			(layer "F.Fab")
		)
		(fp_rect
			(start 2.54 4.2926)
			(end 3.81 -4.2926)
			(stroke
				(width 0)
				(type default)
			)
			(fill no)
			(layer "F.Fab")
		)
		(pad "1" smd rect
			(at 0 -3.1496)
			(size 2.413 2.286)
			(layers "F.Cu" "F.Mask" "F.Paste")
			(net "P3V3_STBY_OUT")
		)
		(pad "2" smd rect
			(at 0 3.1496)
			(size 2.413 2.286)
			(layers "F.Cu" "F.Mask" "F.Paste")
			(net "GND")
		)
		(zone
			(layer "F.Cu")
			(hatch none 0.5)
			(connect_pads
				(clearance 0)
			)
			(min_thickness 0.25)
			(keepout
				(tracks allowed)
				(vias not_allowed)
				(pads allowed)
				(copperpour not_allowed)
				(footprints allowed)
			)
			(placement
				(enabled no)
				(sheetname "")
			)
			(fill
				(thermal_gap 0.5)
				(thermal_bridge_width 0.5)
				(island_removal_mode 0)
			)
			(polygon
				(pts
					(xy 48.76038 -179.423314) (xy 51.78298 -179.423314) (xy 51.78298 -182.318914) (xy 51.78298 -182.649114)
					(xy 48.76038 -182.649114) (xy 48.76038 -182.318914)
				)
			)
		)
		(zone
			(layer "F.Cu")
			(hatch none 0.5)
			(connect_pads
				(clearance 0)
			)
			(min_thickness 0.25)
			(keepout
				(tracks allowed)
				(vias not_allowed)
				(pads allowed)
				(copperpour not_allowed)
				(footprints allowed)
			)
			(placement
				(enabled no)
				(sheetname "")
			)
			(fill
				(thermal_gap 0.5)
				(thermal_bridge_width 0.5)
				(island_removal_mode 0)
			)
			(polygon
				(pts
					(xy 51.78298 -185.709814) (xy 51.78298 -188.618114) (xy 48.76038 -188.618114) (xy 48.76038 -185.722514)
					(xy 48.76038 -185.392314) (xy 51.78298 -185.392314)
				)
			)
		)
	)
)
